(kicad_pcb
	(version 20221018)
	(generator pcbnew)
	(general
    (thickness 0.908)
  )
	(paper "A4")
	(title_block
    (title "HDMI-MIPI Bridge")
    (date "2024-04-24")
    (rev "1.3.2")
		(comment 9 "footprints 78-85 of 121")
	)
	(layers
    (0 "F.Cu" signal)
    (1 "In1.Cu" signal)
    (2 "In2.Cu" signal)
    (31 "B.Cu" signal)
    (32 "B.Adhes" user "B.Adhesive")
    (33 "F.Adhes" user "F.Adhesive")
    (34 "B.Paste" user)
    (35 "F.Paste" user)
    (36 "B.SilkS" user "B.Silkscreen")
    (37 "F.SilkS" user "F.Silkscreen")
    (38 "B.Mask" user)
    (39 "F.Mask" user)
    (40 "Dwgs.User" user "User.Drawings")
    (41 "Cmts.User" user "User.Comments")
    (42 "Eco1.User" user "User.Eco1")
    (43 "Eco2.User" user "User.Eco2")
    (44 "Edge.Cuts" user)
    (45 "Margin" user)
    (46 "B.CrtYd" user "B.Courtyard")
    (47 "F.CrtYd" user "F.Courtyard")
    (48 "B.Fab" user)
    (49 "F.Fab" user)
  )
	(footprint "antmicro-footprints:C_0402_1005Metric" (layer "F.Cu")
    (at 163.79 111.84)
    (descr "Capacitor SMD 0402")
    (tags "capacitor SMD 0402")
    (property "Author" "Antmicro")
    (property "Dielectric" "")
    (property "License" "Apache-2.0")
    (property "MPN" "0402B471K250CT")
    (property "Manufacturer" "Walsin")
    (property "Public" "False")
    (property "Sheetfile" "channel2.kicad_sch")
    (property "Sheetname" "Channel 2")
    (property "Val" "470p")
    (property "Voltage" "")
    (property "ki_description" "SMD Multilayer Ceramic Capacitor, General Purpose, 470 pF, 25 V, 0402 [1005 Metric], ± 10%, X7R")
    (property "ki_keywords" "0402, SMT, CAPACITOR, PASSIVE, MLCC")
    (attr smd)
    (fp_text reference "C49" (at -3.69 6.96) (layer "F.SilkS")
        (effects (font (size 0.65 0.65) (thickness 0.13)) (justify left bottom))
    )
    (fp_text value "C_470p_0402" (at 0 1.4) (layer "F.Fab")
        (effects (font (size 0.65 0.65) (thickness 0.13)) (justify left bottom))
    )
    (fp_text user "License: Apache-2.0" (at -0.932 5.17) (layer "F.Fab") hide
        (effects (font (size 0.7 0.7) (thickness 0.15)) (justify left bottom))
    )
    (fp_text user "Author: Antmicro" (at -0.932 4.17) (layer "F.Fab") hide
        (effects (font (size 0.7 0.7) (thickness 0.15)) (justify left bottom))
    )
    (fp_text user "${REFERENCE}" (at -0.932 3.168) (layer "F.Fab") hide
        (effects (font (size 0.7 0.7) (thickness 0.15)) (justify left bottom))
    )
    (fp_rect (start -0.925 -0.47) (end 0.925 0.47)
      (stroke (width 0.05) (type default)) (fill none) (layer "F.CrtYd"))
    (fp_line (start -0.494 -0.25) (end 0.504 -0.25)
      (stroke (width 0.15) (type solid)) (layer "F.Fab"))
    (fp_line (start -0.494 0.248) (end -0.494 -0.25)
      (stroke (width 0.15) (type solid)) (layer "F.Fab"))
    (fp_line (start 0.504 -0.25) (end 0.504 0.248)
      (stroke (width 0.15) (type solid)) (layer "F.Fab"))
    (fp_line (start 0.504 0.248) (end -0.494 0.248)
      (stroke (width 0.15) (type solid)) (layer "F.Fab"))
    (pad "1" smd roundrect (at -0.48 0) (size 0.59 0.64) (layers "F.Cu" "F.Paste" "F.Mask") (roundrect_rratio 0.25)
      (net 110 "Net-(C49-Pad1)") (pintype "passive"))
    (pad "2" smd roundrect (at 0.48 0) (size 0.59 0.64) (layers "F.Cu" "F.Paste" "F.Mask") (roundrect_rratio 0.25)
      (net 2 "GND") (pintype "passive"))
  )
	(footprint "antmicro-footprints:C_0603_1608Metric" (layer "F.Cu")
    (at 141.3 119.9 -90)
    (descr "Capacitor SMD 0603")
    (tags "capacitor 0603")
    (property "Author" "Antmicro")
    (property "Dielectric" "template_dielectric")
    (property "License" "Apache-2.0")
    (property "MPN" "GRM188R61A106KE69D")
    (property "Manufacturer" "Murata")
    (property "Public" "False")
    (property "Sheetfile" "channel1.kicad_sch")
    (property "Sheetname" "Channel 1")
    (property "Val" "10u")
    (property "Voltage" "")
    (property "ki_description" "SMD Multilayer Ceramic Capacitor, 10 µF, 10 V, 0603 [1608 Metric], ± 10%, X5R, GRM Series")
    (property "ki_keywords" "0603, SMT, CAPACITOR, PASSIVE, CERAMIC, MLCC")
    (attr smd)
    (fp_text reference "C18" (at -1 0.6 90) (layer "F.SilkS")
        (effects (font (size 0.65 0.65) (thickness 0.13)) (justify right bottom))
    )
    (fp_text value "C_10u_0603" (at 0 1.6 90) (layer "F.Fab")
        (effects (font (size 0.65 0.65) (thickness 0.13)) (justify right bottom))
    )
    (fp_text user "License: Apache-2.0" (at -1.682 5.895 90) (layer "F.Fab") hide
        (effects (font (size 0.7 0.7) (thickness 0.15)) (justify right bottom))
    )
    (fp_text user "Author: Antmicro" (at -1.682 4.894 90) (layer "F.Fab") hide
        (effects (font (size 0.7 0.7) (thickness 0.15)) (justify right bottom))
    )
    (fp_text user "${REFERENCE}" (at -1.682 3.895 90) (layer "F.Fab") hide
        (effects (font (size 0.7 0.7) (thickness 0.15)) (justify right bottom))
    )
    (fp_line (start -0.15 -0.4) (end 0.15 -0.4)
      (stroke (width 0.15) (type solid)) (layer "F.SilkS"))
    (fp_line (start -0.15 0.4) (end 0.15 0.4)
      (stroke (width 0.15) (type solid)) (layer "F.SilkS"))
    (fp_rect (start -1.25 -0.65) (end 1.25 0.65)
      (stroke (width 0.05) (type solid)) (fill none) (layer "F.CrtYd"))
    (fp_rect (start -0.8 -0.4) (end 0.8 0.4)
      (stroke (width 0.15) (type solid)) (fill none) (layer "F.Fab"))
    (pad "1" smd roundrect (at -0.7 0 270) (size 0.8 1) (layers "F.Cu" "F.Paste" "F.Mask") (roundrect_rratio 0.2)
      (net 2 "GND") (pintype "passive"))
    (pad "2" smd roundrect (at 0.7 0 270) (size 0.8 1) (layers "F.Cu" "F.Paste" "F.Mask") (roundrect_rratio 0.2)
      (net 9 "+3V3") (pintype "passive"))
  )
	(footprint "antmicro-footprints:C_0402_1005Metric" (layer "F.Cu")
    (at 139.8 111.8)
    (descr "Capacitor SMD 0402")
    (tags "capacitor SMD 0402")
    (property "Author" "Antmicro")
    (property "Dielectric" "")
    (property "License" "Apache-2.0")
    (property "MPN" "0402B471K250CT")
    (property "Manufacturer" "Walsin")
    (property "Public" "False")
    (property "Sheetfile" "channel1.kicad_sch")
    (property "Sheetname" "Channel 1")
    (property "Val" "470p")
    (property "Voltage" "")
    (property "ki_description" "SMD Multilayer Ceramic Capacitor, General Purpose, 470 pF, 25 V, 0402 [1005 Metric], ± 10%, X7R")
    (property "ki_keywords" "0402, SMT, CAPACITOR, PASSIVE, MLCC")
    (attr smd)
    (fp_text reference "C6" (at -3.7 5.7) (layer "F.SilkS")
        (effects (font (size 0.65 0.65) (thickness 0.13)) (justify left bottom))
    )
    (fp_text value "C_470p_0402" (at 0 1.4) (layer "F.Fab")
        (effects (font (size 0.65 0.65) (thickness 0.13)) (justify left bottom))
    )
    (fp_text user "License: Apache-2.0" (at -0.932 5.17) (layer "F.Fab") hide
        (effects (font (size 0.7 0.7) (thickness 0.15)) (justify left bottom))
    )
    (fp_text user "Author: Antmicro" (at -0.932 4.17) (layer "F.Fab") hide
        (effects (font (size 0.7 0.7) (thickness 0.15)) (justify left bottom))
    )
    (fp_text user "${REFERENCE}" (at -0.932 3.168) (layer "F.Fab") hide
        (effects (font (size 0.7 0.7) (thickness 0.15)) (justify left bottom))
    )
    (fp_rect (start -0.925 -0.47) (end 0.925 0.47)
      (stroke (width 0.05) (type default)) (fill none) (layer "F.CrtYd"))
    (fp_line (start -0.494 -0.25) (end 0.504 -0.25)
      (stroke (width 0.15) (type solid)) (layer "F.Fab"))
    (fp_line (start -0.494 0.248) (end -0.494 -0.25)
      (stroke (width 0.15) (type solid)) (layer "F.Fab"))
    (fp_line (start 0.504 -0.25) (end 0.504 0.248)
      (stroke (width 0.15) (type solid)) (layer "F.Fab"))
    (fp_line (start 0.504 0.248) (end -0.494 0.248)
      (stroke (width 0.15) (type solid)) (layer "F.Fab"))
    (pad "1" smd roundrect (at -0.48 0) (size 0.59 0.64) (layers "F.Cu" "F.Paste" "F.Mask") (roundrect_rratio 0.25)
      (net 7 "Net-(C10-Pad2)") (pintype "passive"))
    (pad "2" smd roundrect (at 0.48 0) (size 0.59 0.64) (layers "F.Cu" "F.Paste" "F.Mask") (roundrect_rratio 0.25)
      (net 2 "GND") (pintype "passive"))
  )
	(footprint "antmicro-footprints:C_0402_1005Metric" (layer "F.Cu")
    (at 139.8 110.8)
    (descr "Capacitor SMD 0402")
    (tags "capacitor SMD 0402")
    (property "Author" "Antmicro")
    (property "Dielectric" "")
    (property "License" "Apache-2.0")
    (property "MPN" "0402B471K250CT")
    (property "Manufacturer" "Walsin")
    (property "Public" "False")
    (property "Sheetfile" "channel1.kicad_sch")
    (property "Sheetname" "Channel 1")
    (property "Val" "470p")
    (property "Voltage" "")
    (property "ki_description" "SMD Multilayer Ceramic Capacitor, General Purpose, 470 pF, 25 V, 0402 [1005 Metric], ± 10%, X7R")
    (property "ki_keywords" "0402, SMT, CAPACITOR, PASSIVE, MLCC")
    (attr smd)
    (fp_text reference "C4" (at -3.7 5.7) (layer "F.SilkS")
        (effects (font (size 0.65 0.65) (thickness 0.13)) (justify left bottom))
    )
    (fp_text value "C_470p_0402" (at 0 1.4) (layer "F.Fab")
        (effects (font (size 0.65 0.65) (thickness 0.13)) (justify left bottom))
    )
    (fp_text user "${REFERENCE}" (at -0.932 3.168) (layer "F.Fab") hide
        (effects (font (size 0.7 0.7) (thickness 0.15)) (justify left bottom))
    )
    (fp_text user "License: Apache-2.0" (at -0.932 5.17) (layer "F.Fab") hide
        (effects (font (size 0.7 0.7) (thickness 0.15)) (justify left bottom))
    )
    (fp_text user "Author: Antmicro" (at -0.932 4.17) (layer "F.Fab") hide
        (effects (font (size 0.7 0.7) (thickness 0.15)) (justify left bottom))
    )
    (fp_rect (start -0.925 -0.47) (end 0.925 0.47)
      (stroke (width 0.05) (type default)) (fill none) (layer "F.CrtYd"))
    (fp_line (start -0.494 -0.25) (end 0.504 -0.25)
      (stroke (width 0.15) (type solid)) (layer "F.Fab"))
    (fp_line (start -0.494 0.248) (end -0.494 -0.25)
      (stroke (width 0.15) (type solid)) (layer "F.Fab"))
    (fp_line (start 0.504 -0.25) (end 0.504 0.248)
      (stroke (width 0.15) (type solid)) (layer "F.Fab"))
    (fp_line (start 0.504 0.248) (end -0.494 0.248)
      (stroke (width 0.15) (type solid)) (layer "F.Fab"))
    (pad "1" smd roundrect (at -0.48 0) (size 0.59 0.64) (layers "F.Cu" "F.Paste" "F.Mask") (roundrect_rratio 0.25)
      (net 5 "Net-(U1B-AVDD25)") (pintype "passive"))
    (pad "2" smd roundrect (at 0.48 0) (size 0.59 0.64) (layers "F.Cu" "F.Paste" "F.Mask") (roundrect_rratio 0.25)
      (net 2 "GND") (pintype "passive"))
  )
	(footprint "antmicro-footprints:C_0402_1005Metric" (layer "F.Cu")
    (at 148.01 110.25 90)
    (descr "Capacitor SMD 0402")
    (tags "capacitor SMD 0402")
    (property "Author" "Antmicro")
    (property "Dielectric" "C0G")
    (property "License" "Apache-2.0")
    (property "MPN" "C0402C470J5GACTU")
    (property "Manufacturer" "KEMET")
    (property "Public" "False")
    (property "Sheetfile" "channel2.kicad_sch")
    (property "Sheetname" "Channel 2")
    (property "Val" "47p")
    (property "Voltage" "")
    (property "ki_description" "SMD Multilayer Ceramic Capacitor, 47 pF, 50 V, 0402 [1005 Metric], ± 5%, C0G / NP0, C Series KEMET")
    (property "ki_keywords" "0402, SMT, CAPACITOR, PASSIVE, CERAMIC, MLCC")
    (attr smd)
    (fp_text reference "C39" (at 0.05 -1.51 90) (layer "F.SilkS")
        (effects (font (size 0.65 0.65) (thickness 0.13)) (justify right bottom))
    )
    (fp_text value "C_47p_0402" (at 0 1.4 90) (layer "F.Fab")
        (effects (font (size 0.65 0.65) (thickness 0.13)) (justify left bottom))
    )
    (fp_text user "Author: Antmicro" (at -0.932 4.17 90) (layer "F.Fab") hide
        (effects (font (size 0.7 0.7) (thickness 0.15)) (justify left bottom))
    )
    (fp_text user "${REFERENCE}" (at -0.932 3.168 90) (layer "F.Fab") hide
        (effects (font (size 0.7 0.7) (thickness 0.15)) (justify left bottom))
    )
    (fp_text user "License: Apache-2.0" (at -0.932 5.17 90) (layer "F.Fab") hide
        (effects (font (size 0.7 0.7) (thickness 0.15)) (justify left bottom))
    )
    (fp_rect (start -0.925 -0.47) (end 0.925 0.47)
      (stroke (width 0.05) (type default)) (fill none) (layer "F.CrtYd"))
    (fp_line (start -0.494 -0.25) (end 0.504 -0.25)
      (stroke (width 0.15) (type solid)) (layer "F.Fab"))
    (fp_line (start -0.494 0.248) (end -0.494 -0.25)
      (stroke (width 0.15) (type solid)) (layer "F.Fab"))
    (fp_line (start 0.504 -0.25) (end 0.504 0.248)
      (stroke (width 0.15) (type solid)) (layer "F.Fab"))
    (fp_line (start 0.504 0.248) (end -0.494 0.248)
      (stroke (width 0.15) (type solid)) (layer "F.Fab"))
    (pad "1" smd roundrect (at -0.48 0 90) (size 0.59 0.64) (layers "F.Cu" "F.Paste" "F.Mask") (roundrect_rratio 0.25)
      (net 2 "GND") (pintype "passive"))
    (pad "2" smd roundrect (at 0.48 0 90) (size 0.59 0.64) (layers "F.Cu" "F.Paste" "F.Mask") (roundrect_rratio 0.25)
      (net 30 "Net-(Y2-EN)") (pintype "passive"))
  )
	(footprint "antmicro-footprints:C_0402_1005Metric" (layer "F.Cu")
    (at 124 105.4 -90)
    (descr "Capacitor SMD 0402")
    (tags "capacitor SMD 0402")
    (property "Author" "Antmicro")
    (property "Dielectric" "X5R")
    (property "License" "Apache-2.0")
    (property "MPN" "GRM155R61H104KE14D")
    (property "Manufacturer" "Murata")
    (property "Public" "False")
    (property "Sheetfile" "channel1.kicad_sch")
    (property "Sheetname" "Channel 1")
    (property "Val" "100n")
    (property "Voltage" "50V")
    (property "ki_description" "SMD Multilayer Ceramic Capacitor, 0.1 µF, 50 V, 0402 [1005 Metric], ± 10%, X5R, GRM Series")
    (property "ki_keywords" "0402, SMT, CAPACITOR, PASSIVE, CERAMIC, MLCC")
    (attr smd)
    (fp_text reference "C12" (at -3 -0.4 90) (layer "F.SilkS")
        (effects (font (size 0.65 0.65) (thickness 0.13)) (justify right bottom))
    )
    (fp_text value "C_100n_0402" (at 0 1.4 90) (layer "F.Fab")
        (effects (font (size 0.65 0.65) (thickness 0.13)) (justify right bottom))
    )
    (fp_text user "${REFERENCE}" (at -0.932 3.168 90) (layer "F.Fab") hide
        (effects (font (size 0.7 0.7) (thickness 0.15)) (justify right bottom))
    )
    (fp_text user "License: Apache-2.0" (at -0.932 5.17 90) (layer "F.Fab") hide
        (effects (font (size 0.7 0.7) (thickness 0.15)) (justify right bottom))
    )
    (fp_text user "Author: Antmicro" (at -0.932 4.17 90) (layer "F.Fab") hide
        (effects (font (size 0.7 0.7) (thickness 0.15)) (justify right bottom))
    )
    (fp_rect (start -0.925 -0.47) (end 0.925 0.47)
      (stroke (width 0.05) (type default)) (fill none) (layer "F.CrtYd"))
    (fp_line (start -0.494 -0.25) (end 0.504 -0.25)
      (stroke (width 0.15) (type solid)) (layer "F.Fab"))
    (fp_line (start -0.494 0.248) (end -0.494 -0.25)
      (stroke (width 0.15) (type solid)) (layer "F.Fab"))
    (fp_line (start 0.504 -0.25) (end 0.504 0.248)
      (stroke (width 0.15) (type solid)) (layer "F.Fab"))
    (fp_line (start 0.504 0.248) (end -0.494 0.248)
      (stroke (width 0.15) (type solid)) (layer "F.Fab"))
    (pad "1" smd roundrect (at -0.48 0 270) (size 0.59 0.64) (layers "F.Cu" "F.Paste" "F.Mask") (roundrect_rratio 0.25)
      (net 2 "GND") (pintype "passive"))
    (pad "2" smd roundrect (at 0.48 0 270) (size 0.59 0.64) (layers "F.Cu" "F.Paste" "F.Mask") (roundrect_rratio 0.25)
      (net 9 "+3V3") (pintype "passive"))
  )
	(footprint "antmicro-footprints:C_0402_1005Metric" (layer "F.Cu")
    (at 131 113.4)
    (descr "Capacitor SMD 0402")
    (tags "capacitor SMD 0402")
    (property "Author" "Antmicro")
    (property "Dielectric" "X5R")
    (property "License" "Apache-2.0")
    (property "MPN" "GRM155R61H104KE14D")
    (property "Manufacturer" "Murata")
    (property "Public" "False")
    (property "Sheetfile" "channel1.kicad_sch")
    (property "Sheetname" "Channel 1")
    (property "Val" "100n")
    (property "Voltage" "50V")
    (property "ki_description" "SMD Multilayer Ceramic Capacitor, 0.1 µF, 50 V, 0402 [1005 Metric], ± 10%, X5R, GRM Series")
    (property "ki_keywords" "0402, SMT, CAPACITOR, PASSIVE, CERAMIC, MLCC")
    (attr smd)
    (fp_text reference "C29" (at -1.6 7.6) (layer "F.SilkS")
        (effects (font (size 0.65 0.65) (thickness 0.13)) (justify left bottom))
    )
    (fp_text value "C_100n_0402" (at 0 1.4) (layer "F.Fab")
        (effects (font (size 0.65 0.65) (thickness 0.13)) (justify left bottom))
    )
    (fp_text user "License: Apache-2.0" (at -0.932 5.17) (layer "F.Fab") hide
        (effects (font (size 0.7 0.7) (thickness 0.15)) (justify left bottom))
    )
    (fp_text user "Author: Antmicro" (at -0.932 4.17) (layer "F.Fab") hide
        (effects (font (size 0.7 0.7) (thickness 0.15)) (justify left bottom))
    )
    (fp_text user "${REFERENCE}" (at -0.932 3.168) (layer "F.Fab") hide
        (effects (font (size 0.7 0.7) (thickness 0.15)) (justify left bottom))
    )
    (fp_rect (start -0.925 -0.47) (end 0.925 0.47)
      (stroke (width 0.05) (type default)) (fill none) (layer "F.CrtYd"))
    (fp_line (start -0.494 -0.25) (end 0.504 -0.25)
      (stroke (width 0.15) (type solid)) (layer "F.Fab"))
    (fp_line (start -0.494 0.248) (end -0.494 -0.25)
      (stroke (width 0.15) (type solid)) (layer "F.Fab"))
    (fp_line (start 0.504 -0.25) (end 0.504 0.248)
      (stroke (width 0.15) (type solid)) (layer "F.Fab"))
    (fp_line (start 0.504 0.248) (end -0.494 0.248)
      (stroke (width 0.15) (type solid)) (layer "F.Fab"))
    (pad "1" smd roundrect (at -0.48 0) (size 0.59 0.64) (layers "F.Cu" "F.Paste" "F.Mask") (roundrect_rratio 0.25)
      (net 2 "GND") (pintype "passive"))
    (pad "2" smd roundrect (at 0.48 0) (size 0.59 0.64) (layers "F.Cu" "F.Paste" "F.Mask") (roundrect_rratio 0.25)
      (net 21 "Net-(U1B-VDDIO2)") (pintype "passive"))
  )
	(footprint "antmicro-footprints:C_0402_1005Metric" (layer "F.Cu")
    (at 153.6 111.855 90)
    (descr "Capacitor SMD 0402")
    (tags "capacitor SMD 0402")
    (property "Author" "Antmicro")
    (property "Dielectric" "C0G")
    (property "License" "Apache-2.0")
    (property "MPN" "C0402C470J5GACTU")
    (property "Manufacturer" "KEMET")
    (property "Public" "False")
    (property "Sheetfile" "channel2.kicad_sch")
    (property "Sheetname" "Channel 2")
    (property "Val" "47p")
    (property "Voltage" "")
    (property "ki_description" "SMD Multilayer Ceramic Capacitor, 47 pF, 50 V, 0402 [1005 Metric], ± 5%, C0G / NP0, C Series KEMET")
    (property "ki_keywords" "0402, SMT, CAPACITOR, PASSIVE, CERAMIC, MLCC")
    (attr smd)
    (fp_text reference "C44" (at 0.855 0.2 270) (layer "F.SilkS")
        (effects (font (size 0.65 0.65) (thickness 0.13)) (justify left bottom))
    )
    (fp_text value "C_47p_0402" (at 0 1.4 90) (layer "F.Fab")
        (effects (font (size 0.65 0.65) (thickness 0.13)) (justify left bottom))
    )
    (fp_text user "${REFERENCE}" (at -0.932 3.168 90) (layer "F.Fab") hide
        (effects (font (size 0.7 0.7) (thickness 0.15)) (justify left bottom))
    )
    (fp_text user "Author: Antmicro" (at -0.932 4.17 90) (layer "F.Fab") hide
        (effects (font (size 0.7 0.7) (thickness 0.15)) (justify left bottom))
    )
    (fp_text user "License: Apache-2.0" (at -0.932 5.17 90) (layer "F.Fab") hide
        (effects (font (size 0.7 0.7) (thickness 0.15)) (justify left bottom))
    )
    (fp_rect (start -0.925 -0.47) (end 0.925 0.47)
      (stroke (width 0.05) (type default)) (fill none) (layer "F.CrtYd"))
    (fp_line (start -0.494 -0.25) (end 0.504 -0.25)
      (stroke (width 0.15) (type solid)) (layer "F.Fab"))
    (fp_line (start -0.494 0.248) (end -0.494 -0.25)
      (stroke (width 0.15) (type solid)) (layer "F.Fab"))
    (fp_line (start 0.504 -0.25) (end 0.504 0.248)
      (stroke (width 0.15) (type solid)) (layer "F.Fab"))
    (fp_line (start 0.504 0.248) (end -0.494 0.248)
      (stroke (width 0.15) (type solid)) (layer "F.Fab"))
    (pad "1" smd roundrect (at -0.48 0 90) (size 0.59 0.64) (layers "F.Cu" "F.Paste" "F.Mask") (roundrect_rratio 0.25)
      (net 2 "GND") (pintype "passive"))
    (pad "2" smd roundrect (at 0.48 0 90) (size 0.59 0.64) (layers "F.Cu" "F.Paste" "F.Mask") (roundrect_rratio 0.25)
      (net 31 "Net-(Y2-OUT)") (pintype "passive"))
  )
)
